# T6G (Grand Teton) — schematic netlist excerpt (pin names and nets, part order shuffled) for the footprints in the layout excerpt that follows; sources: Cadence DE-HDL packaged netlist, KiCad conversion of 04192023_DAF0TMB3IC0_F0TG_MB_C_brd_V02_OCP.brd

R643  Q_RES  1K 1% EMPTY  pkg 0402LF  page 362 : A = P3V3_AUX ; B = PWRGD_P0V9_RETIMER_CPU0_R
Y3  Q_CRYSTAL  32.768KHZ IC  pkg SMLF  page 28 : \1\ = XTAL_CPU0_X32K_X1 ; \2\ = XTAL_CPU0_X32K_X2

(kicad_pcb
	(version 20260206)
	(generator "pcbnew")
	(generator_version "10.0")
	(general
		(thickness 1.6)
		(legacy_teardrops no)
	)
	(paper "A4")
	(title_block
		(title "04192023_DAF0TMB3IC0_F0TG_MB_C_brd_V02_OCP.brd")
		(comment 1 "Grand Teton / footprints 6754-6755 of 8354")
	)
	(layers
		(0 "F.Cu" signal "TOP")
		(4 "In1.Cu" signal "GND")
		(6 "In2.Cu" signal "IN1")
		(8 "In3.Cu" signal "GND1")
		(10 "In4.Cu" signal "IN2")
		(12 "In5.Cu" signal "GND2")
		(14 "In6.Cu" signal "IN3")
		(16 "In7.Cu" signal "GND3")
		(18 "In8.Cu" signal "VCC")
		(20 "In9.Cu" signal "VCC1")
		(22 "In10.Cu" signal "GND4")
		(24 "In11.Cu" signal "IN4")
		(26 "In12.Cu" signal "GND5")
		(28 "In13.Cu" signal "IN5")
		(30 "In14.Cu" signal "GND6")
		(32 "In15.Cu" signal "IN6")
		(34 "In16.Cu" signal "GND7")
		(2 "B.Cu" signal "BOTTOM")
		(9 "F.Adhes" user "F.Adhesive")
		(11 "B.Adhes" user "B.Adhesive")
		(13 "F.Paste" user "Package Geometry/Pastemask Top")
		(15 "B.Paste" user "Package Geometry/Pastemask Bottom")
		(5 "F.SilkS" user "Ref Des/Silkscreen Top")
		(7 "B.SilkS" user "Ref Des/Silkscreen Bottom")
		(1 "F.Mask" user "Board Geometry/Soldermask Top")
		(3 "B.Mask" user "Board Geometry/Soldermask Bottom")
		(17 "Dwgs.User" user "User.Drawings")
		(19 "Cmts.User" user "User.Comments")
		(21 "Eco1.User" user "User.Eco1")
		(23 "Eco2.User" user "User.Eco2")
		(25 "Edge.Cuts" user "Board Geometry/Outline")
		(27 "Margin" user)
		(31 "F.CrtYd" user "Package Geometry/Place Bound Top")
		(29 "B.CrtYd" user "Package Geometry/Place Bound Bottom")
		(35 "F.Fab" user "Ref Des/Assembly Top")
		(33 "B.Fab" user "Ref Des/Assembly Bottom")
	)
	(footprint ""
		(layer "B.Cu")
		(at 439.020966 -427.089824 180)
		(property "Reference" "R643"
			(at 0 0 0)
			(layer "B.SilkS")
			(hide yes)
			(effects
				(font
					(size 1.27 1.27)
				)
				(justify mirror)
			)
		)
		(property "Value" ""
			(at 0 0 0)
			(layer "B.Fab")
			(effects
				(font
					(size 1.27 1.27)
				)
				(justify mirror)
			)
		)
		(duplicate_pad_numbers_are_jumpers no)
		(fp_line
			(start 0.7874 0.4064)
			(end 0.7874 -0.4064)
			(stroke
				(width 0.1524)
				(type default)
			)
			(layer "B.SilkS")
		)
		(fp_line
			(start 0.7874 -0.4064)
			(end -0.7874 -0.4064)
			(stroke
				(width 0.1524)
				(type default)
			)
			(layer "B.SilkS")
		)
		(fp_line
			(start -0.7874 0.4064)
			(end 0.7874 0.4064)
			(stroke
				(width 0.1524)
				(type default)
			)
			(layer "B.SilkS")
		)
		(fp_line
			(start -0.7874 -0.4064)
			(end -0.7874 0.4064)
			(stroke
				(width 0.1524)
				(type default)
			)
			(layer "B.SilkS")
		)
		(fp_line
			(start 0.67945 0.3048)
			(end 0.67945 -0.305054)
			(stroke
				(width 0.1)
				(type default)
			)
			(layer "B.Fab")
		)
		(fp_line
			(start 0.67945 -0.305054)
			(end 0.12065 -0.305054)
			(stroke
				(width 0.1)
				(type default)
			)
			(layer "B.Fab")
		)
		(fp_line
			(start 0.12065 0.3048)
			(end 0.67945 0.3048)
			(stroke
				(width 0.1)
				(type default)
			)
			(layer "B.Fab")
		)
		(fp_line
			(start 0.12065 0.2794)
			(end 0.12065 0.3048)
			(stroke
				(width 0.1)
				(type default)
			)
			(layer "B.Fab")
		)
		(fp_line
			(start 0.12065 -0.2794)
			(end -0.12065 -0.2794)
			(stroke
				(width 0.1)
				(type default)
			)
			(layer "B.Fab")
		)
		(fp_line
			(start 0.12065 -0.305054)
			(end 0.12065 -0.2794)
			(stroke
				(width 0.1)
				(type default)
			)
			(layer "B.Fab")
		)
		(fp_line
			(start -0.120396 0.3048)
			(end -0.120396 0.2794)
			(stroke
				(width 0.1)
				(type default)
			)
			(layer "B.Fab")
		)
		(fp_line
			(start -0.120396 0.2794)
			(end 0.12065 0.2794)
			(stroke
				(width 0.1)
				(type default)
			)
			(layer "B.Fab")
		)
		(fp_line
			(start -0.12065 -0.2794)
			(end -0.12065 -0.3048)
			(stroke
				(width 0.1)
				(type default)
			)
			(layer "B.Fab")
		)
		(fp_line
			(start -0.12065 -0.3048)
			(end -0.67945 -0.3048)
			(stroke
				(width 0.1)
				(type default)
			)
			(layer "B.Fab")
		)
		(fp_line
			(start -0.67945 0.3048)
			(end -0.120396 0.3048)
			(stroke
				(width 0.1)
				(type default)
			)
			(layer "B.Fab")
		)
		(fp_line
			(start -0.67945 -0.3048)
			(end -0.67945 0.3048)
			(stroke
				(width 0.1)
				(type default)
			)
			(layer "B.Fab")
		)
		(pad "1" smd circle
			(at 0.40005 0)
			(size 0 0)
			(layers "B.Cu" "B.Mask" "B.Paste")
			(net "P3V3_AUX")
		)
		(pad "2" smd circle
			(at -0.40005 0)
			(size 0 0)
			(layers "B.Cu" "B.Mask" "B.Paste")
			(net "PWRGD_P0V9_RETIMER_CPU0_R")
		)
	)
	(footprint ""
		(layer "B.Cu")
		(at 401.650962 -316.917578 180)
		(property "Reference" "Y3"
			(at 1.188974 2.370836 0)
			(unlocked yes)
			(layer "B.SilkS")
			(effects
				(font
					(size 0.7874 0.5842)
					(thickness 0.1524)
				)
				(justify left mirror)
			)
		)
		(property "Value" ""
			(at 0 0 0)
			(layer "B.Fab")
			(effects
				(font
					(size 1.27 1.27)
				)
				(justify mirror)
			)
		)
		(duplicate_pad_numbers_are_jumpers no)
		(fp_line
			(start 1.905 1.0414)
			(end -1.905 1.0414)
			(stroke
				(width 0.1524)
				(type default)
			)
			(layer "B.SilkS")
		)
		(fp_line
			(start 1.905 -1.0414)
			(end 1.905 1.0414)
			(stroke
				(width 0.1524)
				(type default)
			)
			(layer "B.SilkS")
		)
		(fp_line
			(start -1.905 1.0414)
			(end -1.905 -1.0414)
			(stroke
				(width 0.1524)
				(type default)
			)
			(layer "B.SilkS")
		)
		(fp_line
			(start -1.905 -1.0414)
			(end 1.905 -1.0414)
			(stroke
				(width 0.1524)
				(type default)
			)
			(layer "B.SilkS")
		)
		(fp_line
			(start 1.649984 0.824992)
			(end -1.649984 0.824992)
			(stroke
				(width 0.1)
				(type default)
			)
			(layer "B.Fab")
		)
		(fp_line
			(start 1.649984 -0.824992)
			(end 1.649984 0.824992)
			(stroke
				(width 0.1)
				(type default)
			)
			(layer "B.Fab")
		)
		(fp_line
			(start -1.649984 0.824992)
			(end -1.649984 -0.824992)
			(stroke
				(width 0.1)
				(type default)
			)
			(layer "B.Fab")
		)
		(fp_line
			(start -1.649984 -0.824992)
			(end 1.649984 -0.824992)
			(stroke
				(width 0.1)
				(type default)
			)
			(layer "B.Fab")
		)
		(pad "1" smd rect
			(at 1.249934 0)
			(size 1.016 1.8034)
			(layers "B.Cu" "B.Mask" "B.Paste")
			(net "XTAL_CPU0_X32K_X1")
		)
		(pad "2" smd rect
			(at -1.249934 0 180)
			(size 1.016 1.8034)
			(layers "B.Cu" "B.Mask" "B.Paste")
			(net "XTAL_CPU0_X32K_X2")
		)
		(zone
			(layer "B.Cu")
			(hatch none 0.5)
			(connect_pads
				(clearance 0)
			)
			(min_thickness 0.25)
			(keepout
				(tracks not_allowed)
				(vias allowed)
				(pads allowed)
				(copperpour not_allowed)
				(footprints allowed)
			)
			(placement
				(enabled no)
				(sheetname "")
			)
			(fill
				(thermal_gap 0.5)
				(thermal_bridge_width 0.5)
				(island_removal_mode 0)
			)
			(polygon
				(pts
					(xy 400.959828 -315.965078) (xy 400.959828 -317.870078) (xy 402.342096 -317.870078) (xy 402.342096 -315.965078)
				)
			)
		)
	)
)
